(kicad_pcb
	(version 20260206)
	(generator "pcbnew")
	(generator_version "10.0")
	(general
		(thickness 1.6)
		(legacy_teardrops no)
	)
	(paper "A4")
	(title_block
		(title "pdpb — Lightning_PDPB_BRD.brd")
		(comment 1 "Lightning (Wiwynn / Facebook NVMe JBOF) / footprints 809-814 of 1140")
	)
	(layers
		(0 "F.Cu" signal "TOP")
		(4 "In1.Cu" signal "L2GND")
		(6 "In2.Cu" signal "L3")
		(8 "In3.Cu" signal "L4VCC")
		(10 "In4.Cu" signal "L5VCC")
		(12 "In5.Cu" signal "L6")
		(14 "In6.Cu" signal "L7GND")
		(2 "B.Cu" signal "BOTTOM")
		(9 "F.Adhes" user "F.Adhesive")
		(11 "B.Adhes" user "B.Adhesive")
		(13 "F.Paste" user "Package Geometry/Pastemask Top")
		(15 "B.Paste" user "Package Geometry/Pastemask Bottom")
		(5 "F.SilkS" user "Ref Des/Silkscreen Top")
		(7 "B.SilkS" user "Ref Des/Silkscreen Bottom")
		(1 "F.Mask" user "Board Geometry/Soldermask Top")
		(3 "B.Mask" user "Board Geometry/Soldermask Bottom")
		(17 "Dwgs.User" user "User.Drawings")
		(19 "Cmts.User" user "User.Comments")
		(21 "Eco1.User" user "User.Eco1")
		(23 "Eco2.User" user "User.Eco2")
		(25 "Edge.Cuts" user "Board Geometry/Outline")
		(27 "Margin" user)
		(31 "F.CrtYd" user "Package Geometry/Place Bound Top")
		(29 "B.CrtYd" user "Package Geometry/Place Bound Bottom")
		(35 "F.Fab" user "Ref Des/Assembly Top")
		(33 "B.Fab" user "Ref Des/Assembly Bottom")
	)
	(footprint ""
		(layer "F.Cu")
		(at 50.038 -10.795)
		(property "Reference" "Q22"
			(at 0 0 0)
			(layer "F.SilkS")
			(hide yes)
			(effects
				(font
					(size 1.27 1.27)
				)
			)
		)
		(property "Value" "2N7002A-7-GP"
			(at 0.127 -8.9662 0)
			(unlocked yes)
			(layer "F.Fab")
			(hide yes)
			(effects
				(font
					(size 1.016 1.016)
					(thickness 0.1524)
				)
			)
		)
		(property "Device Type" "SOT23DGS2D4H48"
			(at 0.127 -10.4902 0)
			(unlocked yes)
			(layer "F.Fab")
			(hide yes)
			(effects
				(font
					(size 1.016 1.016)
					(thickness 0.1524)
				)
			)
		)
		(duplicate_pad_numbers_are_jumpers no)
		(fp_line
			(start -1.651 -1.778)
			(end -1.651 1.778)
			(stroke
				(width 0.1524)
				(type default)
			)
			(layer "F.SilkS")
		)
		(fp_line
			(start -1.651 1.778)
			(end 1.651 1.778)
			(stroke
				(width 0.1524)
				(type default)
			)
			(layer "F.SilkS")
		)
		(fp_line
			(start 1.651 -1.778)
			(end -1.651 -1.778)
			(stroke
				(width 0.1524)
				(type default)
			)
			(layer "F.SilkS")
		)
		(fp_line
			(start 1.651 1.778)
			(end 1.651 -1.778)
			(stroke
				(width 0.1524)
				(type default)
			)
			(layer "F.SilkS")
		)
		(fp_poly
			(pts
				(xy -1.778 1.8796) (xy -1.778 -1.8796) (xy 1.778 -1.8796) (xy 1.778 1.8796)
			)
			(stroke
				(width 0)
				(type default)
			)
			(fill no)
			(layer "F.CrtYd")
		)
		(fp_poly
			(pts
				(xy -1.778 1.8796) (xy -1.778 -1.8796) (xy 1.778 -1.8796) (xy 1.778 1.8796)
			)
			(stroke
				(width 0)
				(type default)
			)
			(fill no)
			(layer "F.Fab")
		)
		(pad "D" smd custom
			(at 0 -0.9525)
			(size 0.1905 0.1905)
			(layers "F.Cu" "F.Mask" "F.Paste")
			(net "SW_SSD14_R")
			(options
				(clearance outline)
				(anchor circle)
			)
			(primitives
				(gr_poly
					(pts
						(arc
							(start -0.1778 0.5715)
							(mid -0.321484 0.511984)
							(end -0.381 0.3683)
						)
						(arc
							(start -0.381 -0.3683)
							(mid -0.321484 -0.511984)
							(end -0.1778 -0.5715)
						)
						(arc
							(start 0.1778 -0.5715)
							(mid 0.321484 -0.511984)
							(end 0.381 -0.3683)
						)
						(arc
							(start 0.381 0.3683)
							(mid 0.321484 0.511984)
							(end 0.1778 0.5715)
						)
					)
					(width 0)
					(fill yes)
				)
			)
		)
		(pad "G" smd custom
			(at -0.98425 0.9525)
			(size 0.1905 0.1905)
			(layers "F.Cu" "F.Mask" "F.Paste")
			(net "SSD14_PWREN")
			(options
				(clearance outline)
				(anchor circle)
			)
			(primitives
				(gr_poly
					(pts
						(arc
							(start -0.1778 0.5715)
							(mid -0.321484 0.511984)
							(end -0.381 0.3683)
						)
						(arc
							(start -0.381 -0.3683)
							(mid -0.321484 -0.511984)
							(end -0.1778 -0.5715)
						)
						(arc
							(start 0.1778 -0.5715)
							(mid 0.321484 -0.511984)
							(end 0.381 -0.3683)
						)
						(arc
							(start 0.381 0.3683)
							(mid 0.321484 0.511984)
							(end 0.1778 0.5715)
						)
					)
					(width 0)
					(fill yes)
				)
			)
		)
		(pad "S" smd custom
			(at 0.98425 0.9525)
			(size 0.1905 0.1905)
			(layers "F.Cu" "F.Mask" "F.Paste")
			(net "GND")
			(options
				(clearance outline)
				(anchor circle)
			)
			(primitives
				(gr_poly
					(pts
						(arc
							(start -0.1778 0.5715)
							(mid -0.321484 0.511984)
							(end -0.381 0.3683)
						)
						(arc
							(start -0.381 -0.3683)
							(mid -0.321484 -0.511984)
							(end -0.1778 -0.5715)
						)
						(arc
							(start 0.1778 -0.5715)
							(mid 0.321484 -0.511984)
							(end 0.381 -0.3683)
						)
						(arc
							(start 0.381 0.3683)
							(mid 0.321484 0.511984)
							(end 0.1778 0.5715)
						)
					)
					(width 0)
					(fill yes)
				)
			)
		)
	)
	(footprint ""
		(layer "F.Cu")
		(at 24.257 -464.82 -90)
		(property "Reference" "R117"
			(at 0 0 270)
			(layer "F.SilkS")
			(hide yes)
			(effects
				(font
					(size 1.27 1.27)
				)
			)
		)
		(property "Value" "330R2F-GP"
			(at 0.064008 -3.993896 270)
			(unlocked yes)
			(layer "F.Fab")
			(hide yes)
			(effects
				(font
					(size 1.016 1.016)
					(thickness 0.1524)
				)
			)
		)
		(property "Device Type" "R402H16"
			(at 0.064008 -5.517896 270)
			(unlocked yes)
			(layer "F.Fab")
			(hide yes)
			(effects
				(font
					(size 1.016 1.016)
					(thickness 0.1524)
				)
			)
		)
		(duplicate_pad_numbers_are_jumpers no)
		(fp_line
			(start -0.508 -0.9398)
			(end -0.508 0.9398)
			(stroke
				(width 0.1524)
				(type default)
			)
			(layer "F.SilkS")
		)
		(fp_line
			(start 0.508 -0.9398)
			(end -0.508 -0.9398)
			(stroke
				(width 0.1524)
				(type default)
			)
			(layer "F.SilkS")
		)
		(fp_rect
			(start -0.508 0.9398)
			(end 0.508 -0.9398)
			(stroke
				(width 0)
				(type default)
			)
			(fill no)
			(layer "F.CrtYd")
		)
		(fp_rect
			(start -0.508 0.9398)
			(end 0.508 -0.9398)
			(stroke
				(width 0)
				(type default)
			)
			(fill no)
			(layer "F.Fab")
		)
		(pad "1" smd custom
			(at 0 -0.4445 270)
			(size 0.1397 0.1397)
			(layers "F.Cu" "F.Mask" "F.Paste")
			(net "P3V3")
			(options
				(clearance outline)
				(anchor circle)
			)
			(primitives
				(gr_poly
					(pts
						(arc
							(start -0.1778 -0.2794)
							(mid -0.249642 -0.249642)
							(end -0.2794 -0.1778)
						)
						(arc
							(start -0.2794 0.1778)
							(mid -0.249642 0.249642)
							(end -0.1778 0.2794)
						)
						(arc
							(start 0.1778 0.2794)
							(mid 0.249642 0.249642)
							(end 0.2794 0.1778)
						)
						(arc
							(start 0.2794 -0.1778)
							(mid 0.249642 -0.249642)
							(end 0.1778 -0.2794)
						)
					)
					(width 0)
					(fill yes)
				)
			)
		)
		(pad "2" smd custom
			(at 0 0.4445 270)
			(size 0.1397 0.1397)
			(layers "F.Cu" "F.Mask" "F.Paste")
			(net "DRV_ATTN_10")
			(options
				(clearance outline)
				(anchor circle)
			)
			(primitives
				(gr_poly
					(pts
						(arc
							(start -0.1778 -0.2794)
							(mid -0.249642 -0.249642)
							(end -0.2794 -0.1778)
						)
						(arc
							(start -0.2794 0.1778)
							(mid -0.249642 0.249642)
							(end -0.1778 0.2794)
						)
						(arc
							(start 0.1778 0.2794)
							(mid 0.249642 0.249642)
							(end 0.2794 0.1778)
						)
						(arc
							(start 0.2794 -0.1778)
							(mid 0.249642 -0.249642)
							(end 0.1778 -0.2794)
						)
					)
					(width 0)
					(fill yes)
				)
			)
		)
	)
	(footprint ""
		(layer "F.Cu")
		(at 88.138 -115.062)
		(property "Reference" "R9615"
			(at 0 0 0)
			(layer "F.SilkS")
			(hide yes)
			(effects
				(font
					(size 1.27 1.27)
				)
			)
		)
		(property "Value" "10R2F-L-GP"
			(at 0.064008 -3.993896 0)
			(unlocked yes)
			(layer "F.Fab")
			(hide yes)
			(effects
				(font
					(size 1.016 1.016)
					(thickness 0.1524)
				)
			)
		)
		(property "Device Type" "R402H14"
			(at 0.064008 -5.517896 0)
			(unlocked yes)
			(layer "F.Fab")
			(hide yes)
			(effects
				(font
					(size 1.016 1.016)
					(thickness 0.1524)
				)
			)
		)
		(duplicate_pad_numbers_are_jumpers no)
		(fp_line
			(start -0.508 -0.9398)
			(end -0.508 0.9398)
			(stroke
				(width 0.1524)
				(type default)
			)
			(layer "F.SilkS")
		)
		(fp_line
			(start 0.508 -0.9398)
			(end -0.508 -0.9398)
			(stroke
				(width 0.1524)
				(type default)
			)
			(layer "F.SilkS")
		)
		(fp_rect
			(start -0.508 0.9398)
			(end 0.508 -0.9398)
			(stroke
				(width 0)
				(type default)
			)
			(fill no)
			(layer "F.CrtYd")
		)
		(fp_rect
			(start -0.508 0.9398)
			(end 0.508 -0.9398)
			(stroke
				(width 0)
				(type default)
			)
			(fill no)
			(layer "F.Fab")
		)
		(pad "1" smd custom
			(at 0 -0.4445)
			(size 0.1397 0.1397)
			(layers "F.Cu" "F.Mask" "F.Paste")
			(net "SSD13_CLK0_OE_N")
			(options
				(clearance outline)
				(anchor circle)
			)
			(primitives
				(gr_poly
					(pts
						(arc
							(start -0.1778 -0.2794)
							(mid -0.249642 -0.249642)
							(end -0.2794 -0.1778)
						)
						(arc
							(start -0.2794 0.1778)
							(mid -0.249642 0.249642)
							(end -0.1778 0.2794)
						)
						(arc
							(start 0.1778 0.2794)
							(mid 0.249642 0.249642)
							(end 0.2794 0.1778)
						)
						(arc
							(start 0.2794 -0.1778)
							(mid 0.249642 -0.249642)
							(end 0.1778 -0.2794)
						)
					)
					(width 0)
					(fill yes)
				)
			)
		)
		(pad "2" smd custom
			(at 0 0.4445)
			(size 0.1397 0.1397)
			(layers "F.Cu" "F.Mask" "F.Paste")
			(net "SSD13_CLK0_OE_R_N")
			(options
				(clearance outline)
				(anchor circle)
			)
			(primitives
				(gr_poly
					(pts
						(arc
							(start -0.1778 -0.2794)
							(mid -0.249642 -0.249642)
							(end -0.2794 -0.1778)
						)
						(arc
							(start -0.2794 0.1778)
							(mid -0.249642 0.249642)
							(end -0.1778 0.2794)
						)
						(arc
							(start 0.1778 0.2794)
							(mid 0.249642 0.249642)
							(end 0.2794 0.1778)
						)
						(arc
							(start 0.2794 -0.1778)
							(mid 0.249642 -0.249642)
							(end 0.1778 -0.2794)
						)
					)
					(width 0)
					(fill yes)
				)
			)
		)
	)
	(footprint ""
		(layer "F.Cu")
		(at 102.616 -437.134 90)
		(property "Reference" "R9055"
			(at 0 0 90)
			(layer "F.SilkS")
			(hide yes)
			(effects
				(font
					(size 1.27 1.27)
				)
			)
		)
		(property "Value" "27R2F-GP"
			(at 0.064008 -3.993896 90)
			(unlocked yes)
			(layer "F.Fab")
			(hide yes)
			(effects
				(font
					(size 1.016 1.016)
					(thickness 0.1524)
				)
			)
		)
		(property "Device Type" "R402H16"
			(at 0.064008 -5.517896 90)
			(unlocked yes)
			(layer "F.Fab")
			(hide yes)
			(effects
				(font
					(size 1.016 1.016)
					(thickness 0.1524)
				)
			)
		)
		(duplicate_pad_numbers_are_jumpers no)
		(fp_line
			(start 0.508 -0.9398)
			(end -0.508 -0.9398)
			(stroke
				(width 0.1524)
				(type default)
			)
			(layer "F.SilkS")
		)
		(fp_line
			(start -0.508 -0.9398)
			(end -0.508 0.9398)
			(stroke
				(width 0.1524)
				(type default)
			)
			(layer "F.SilkS")
		)
		(fp_rect
			(start -0.508 0.9398)
			(end 0.508 -0.9398)
			(stroke
				(width 0)
				(type default)
			)
			(fill no)
			(layer "F.CrtYd")
		)
		(fp_rect
			(start -0.508 0.9398)
			(end 0.508 -0.9398)
			(stroke
				(width 0)
				(type default)
			)
			(fill no)
			(layer "F.Fab")
		)
		(pad "1" smd custom
			(at 0 -0.4445 90)
			(size 0.1397 0.1397)
			(layers "F.Cu" "F.Mask" "F.Paste")
			(net "PE_CLK_100M_DR0_1_R_P")
			(options
				(clearance outline)
				(anchor circle)
			)
			(primitives
				(gr_poly
					(pts
						(arc
							(start -0.1778 -0.2794)
							(mid -0.249642 -0.249642)
							(end -0.2794 -0.1778)
						)
						(arc
							(start -0.2794 0.1778)
							(mid -0.249642 0.249642)
							(end -0.1778 0.2794)
						)
						(arc
							(start 0.1778 0.2794)
							(mid 0.249642 0.249642)
							(end 0.2794 0.1778)
						)
						(arc
							(start 0.2794 -0.1778)
							(mid 0.249642 -0.249642)
							(end 0.1778 -0.2794)
						)
					)
					(width 0)
					(fill yes)
				)
			)
		)
		(pad "2" smd custom
			(at 0 0.4445 90)
			(size 0.1397 0.1397)
			(layers "F.Cu" "F.Mask" "F.Paste")
			(net "PE_CLK100M_DR0_1_P")
			(options
				(clearance outline)
				(anchor circle)
			)
			(primitives
				(gr_poly
					(pts
						(arc
							(start -0.1778 -0.2794)
							(mid -0.249642 -0.249642)
							(end -0.2794 -0.1778)
						)
						(arc
							(start -0.2794 0.1778)
							(mid -0.249642 0.249642)
							(end -0.1778 0.2794)
						)
						(arc
							(start 0.1778 0.2794)
							(mid 0.249642 0.249642)
							(end 0.2794 0.1778)
						)
						(arc
							(start 0.2794 -0.1778)
							(mid 0.249642 -0.249642)
							(end 0.1778 -0.2794)
						)
					)
					(width 0)
					(fill yes)
				)
			)
		)
	)
	(footprint ""
		(layer "F.Cu")
		(at 226.949 -434.34 -90)
		(property "Reference" "PU2"
			(at 0 0 270)
			(layer "F.SilkS")
			(hide yes)
			(effects
				(font
					(size 1.27 1.27)
				)
			)
		)
		(property "Value" "TPS53312RGTR-GP"
			(at 4.9784 -6.9342 270)
			(unlocked yes)
			(layer "F.Fab")
			(hide yes)
			(effects
				(font
					(size 1.016 1.016)
					(thickness 0.1524)
				)
			)
		)
		(property "Device Type" "QFN16G3-G1D7H40"
			(at 4.9784 -8.4582 270)
			(unlocked yes)
			(layer "F.Fab")
			(hide yes)
			(effects
				(font
					(size 1.016 1.016)
					(thickness 0.1524)
				)
			)
		)
		(duplicate_pad_numbers_are_jumpers no)
		(fp_line
			(start -2.5146 2.5146)
			(end -1.2446 2.5146)
			(stroke
				(width 0.1524)
				(type default)
			)
			(layer "F.SilkS")
		)
		(fp_line
			(start 1.2446 2.5146)
			(end 2.5146 2.5146)
			(stroke
				(width 0.1524)
				(type default)
			)
			(layer "F.SilkS")
		)
		(fp_line
			(start 2.5146 2.5146)
			(end 2.5146 1.2446)
			(stroke
				(width 0.1524)
				(type default)
			)
			(layer "F.SilkS")
		)
		(fp_line
			(start -0.249936 2.262124)
			(end -0.249936 3.024124)
			(stroke
				(width 0.1524)
				(type default)
			)
			(layer "F.SilkS")
		)
		(fp_line
			(start -2.5146 1.2446)
			(end -2.5146 2.5146)
			(stroke
				(width 0.1524)
				(type default)
			)
			(layer "F.SilkS")
		)
		(fp_line
			(start 2.262124 -0.249936)
			(end 2.770124 -0.249936)
			(stroke
				(width 0.1524)
				(type default)
			)
			(layer "F.SilkS")
		)
		(fp_line
			(start -2.262124 -0.750062)
			(end -2.770124 -0.750062)
			(stroke
				(width 0.1524)
				(type default)
			)
			(layer "F.SilkS")
		)
		(fp_line
			(start -2.5146 -2.5146)
			(end -2.5146 -1.2446)
			(stroke
				(width 0.1524)
				(type default)
			)
			(layer "F.SilkS")
		)
		(fp_line
			(start -1.2446 -2.5146)
			(end -2.5146 -2.5146)
			(stroke
				(width 0.1524)
				(type default)
			)
			(layer "F.SilkS")
		)
		(fp_poly
			(pts
				(xy 2.5146 -2.5146) (xy 1.2446 -2.5146) (xy 2.5146 -1.2446)
			)
			(stroke
				(width 0)
				(type default)
			)
			(fill yes)
			(layer "F.SilkS")
		)
		(fp_rect
			(start -1.4986 1.4986)
			(end 1.4986 -1.4986)
			(stroke
				(width 0)
				(type default)
			)
			(fill no)
			(layer "F.CrtYd")
		)
		(fp_poly
			(pts
				(xy 2.5146 -1.4986) (xy -1.4986 -1.4986) (xy -1.4986 1.4986) (xy 1.4986 1.4986) (xy 1.4986 -1.4859)
				(xy 2.5146 -1.4859) (xy 2.5146 2.5146) (xy -2.5146 2.5146) (xy -2.5146 -2.5146) (xy 2.5146 -2.5146)
			)
			(stroke
				(width 0)
				(type default)
			)
			(fill no)
			(layer "F.CrtYd")
		)
		(fp_rect
			(start -2.5146 2.5146)
			(end 2.5146 -2.5146)
			(stroke
				(width 0)
				(type default)
			)
			(fill no)
			(layer "F.Fab")
		)
		(pad "1" smd rect
			(at 0.750062 -1.550924 270)
			(size 0.3048 0.9144)
			(layers "F.Cu" "F.Mask" "F.Paste")
			(net "P3V3_VFB")
		)
		(pad "2" smd rect
			(at 0.249936 -1.538224 270)
			(size 0.3048 0.9398)
			(layers "F.Cu" "F.Mask" "F.Paste")
			(net "P3V3_VRG5")
		)
		(pad "3" smd rect
			(at -0.249936 -1.538224 270)
			(size 0.3048 0.9398)
			(layers "F.Cu" "F.Mask" "F.Paste")
			(net "P3V3_SS")
		)
		(pad "4" smd rect
			(at -0.750062 -1.550924 270)
			(size 0.3048 0.9144)
			(layers "F.Cu" "F.Mask" "F.Paste")
			(net "AGND_P3V3")
		)
		(pad "5" smd rect
			(at -1.550924 -0.750062 270)
			(size 0.9144 0.3048)
			(layers "F.Cu" "F.Mask" "F.Paste")
			(net "TPS53312_P3V3_PG")
		)
		(pad "6" smd rect
			(at -1.538224 -0.249936 270)
			(size 0.9398 0.3048)
			(layers "F.Cu" "F.Mask" "F.Paste")
			(net "P3V3_EN_R")
		)
		(pad "7" smd rect
			(at -1.538224 0.249936 270)
			(size 0.9398 0.3048)
			(layers "F.Cu" "F.Mask" "F.Paste")
			(net "GND")
		)
		(pad "8" smd rect
			(at -1.550924 0.750062 270)
			(size 0.9144 0.3048)
			(layers "F.Cu" "F.Mask" "F.Paste")
			(net "GND")
		)
		(pad "9" smd rect
			(at -0.750062 1.550924 270)
			(size 0.3048 0.9144)
			(layers "F.Cu" "F.Mask" "F.Paste")
			(net "P3V3_SW")
		)
		(pad "10" smd rect
			(at -0.249936 1.538224 270)
			(size 0.3048 0.9398)
			(layers "F.Cu" "F.Mask" "F.Paste")
			(net "P3V3_SW")
		)
		(pad "11" smd rect
			(at 0.249936 1.538224 270)
			(size 0.3048 0.9398)
			(layers "F.Cu" "F.Mask" "F.Paste")
			(net "P3V3_SW")
		)
		(pad "12" smd rect
			(at 0.750062 1.550924 270)
			(size 0.3048 0.9144)
			(layers "F.Cu" "F.Mask" "F.Paste")
			(net "P3V3_VBST")
		)
		(pad "13" smd rect
			(at 1.550924 0.750062 270)
			(size 0.9144 0.3048)
			(layers "F.Cu" "F.Mask" "F.Paste")
			(net "P3V3_VIN")
		)
		(pad "14" smd rect
			(at 1.538224 0.249936 270)
			(size 0.9398 0.3048)
			(layers "F.Cu" "F.Mask" "F.Paste")
			(net "P3V3_VIN")
		)
		(pad "15" smd rect
			(at 1.538224 -0.249936 270)
			(size 0.9398 0.3048)
			(layers "F.Cu" "F.Mask" "F.Paste")
			(net "P3V3_VCC")
		)
		(pad "16" smd rect
			(at 1.550924 -0.750062 270)
			(size 0.9144 0.3048)
			(layers "F.Cu" "F.Mask" "F.Paste")
			(net "P3V3_VO")
		)
		(pad "17" smd rect
			(at 0 0 270)
			(size 1.6764 1.6764)
			(layers "F.Cu" "F.Mask" "F.Paste")
			(net "GND")
		)
	)
	(footprint ""
		(layer "F.Cu")
		(at 86.614 -102.743 180)
		(property "Reference" "C8933"
			(at 0 0 180)
			(layer "F.SilkS")
			(hide yes)
			(effects
				(font
					(size 1.27 1.27)
				)
			)
		)
		(property "Value" "SC1U10V2KX-7-GP"
			(at 1.1811 -2.7051 180)
			(unlocked yes)
			(layer "F.Fab")
			(hide yes)
			(effects
				(font
					(size 1.016 1.016)
					(thickness 0.1524)
				)
			)
		)
		(property "Device Type" "C402H22"
			(at 1.1811 -4.2291 180)
			(unlocked yes)
			(layer "F.Fab")
			(hide yes)
			(effects
				(font
					(size 1.016 1.016)
					(thickness 0.1524)
				)
			)
		)
		(duplicate_pad_numbers_are_jumpers no)
		(fp_rect
			(start -0.4318 0.9525)
			(end 0.4318 -0.9525)
			(stroke
				(width 0)
				(type default)
			)
			(fill no)
			(layer "F.CrtYd")
		)
		(fp_rect
			(start -0.4318 0.9525)
			(end 0.4318 -0.9525)
			(stroke
				(width 0)
				(type default)
			)
			(fill no)
			(layer "F.Fab")
		)
		(pad "1" smd custom
			(at 0 -0.4445 180)
			(size 0.1524 0.1524)
			(layers "F.Cu" "F.Mask" "F.Paste")
			(net "VDDR_4")
			(options
				(clearance outline)
				(anchor circle)
			)
			(primitives
				(gr_poly
					(pts
						(arc
							(start 0.3048 -0.2032)
							(mid 0.275042 -0.275042)
							(end 0.2032 -0.3048)
						)
						(arc
							(start -0.2032 -0.3048)
							(mid -0.275042 -0.275042)
							(end -0.3048 -0.2032)
						)
						(arc
							(start -0.3048 0.2032)
							(mid -0.275042 0.275042)
							(end -0.2032 0.3048)
						)
						(arc
							(start 0.2032 0.3048)
							(mid 0.275042 0.275042)
							(end 0.3048 0.2032)
						)
					)
					(width 0)
					(fill yes)
				)
			)
		)
		(pad "2" smd custom
			(at 0 0.4445 180)
			(size 0.1524 0.1524)
			(layers "F.Cu" "F.Mask" "F.Paste")
			(net "GND")
			(options
				(clearance outline)
				(anchor circle)
			)
			(primitives
				(gr_poly
					(pts
						(arc
							(start 0.3048 -0.2032)
							(mid 0.275042 -0.275042)
							(end 0.2032 -0.3048)
						)
						(arc
							(start -0.2032 -0.3048)
							(mid -0.275042 -0.275042)
							(end -0.3048 -0.2032)
						)
						(arc
							(start -0.3048 0.2032)
							(mid -0.275042 0.275042)
							(end -0.2032 0.3048)
						)
						(arc
							(start 0.2032 0.3048)
							(mid 0.275042 0.275042)
							(end 0.3048 0.2032)
						)
					)
					(width 0)
					(fill yes)
				)
			)
		)
	)
)
